# T6G (Grand Teton) — schematic netlist excerpt (pin names and nets, part order shuffled) for the footprints in the layout excerpt that follows; sources: Cadence DE-HDL packaged netlist, KiCad conversion of 04192023_DAF0TMB3IC0_F0TG_MB_C_brd_V02_OCP.brd

R811  Q_RES  1K 1% CHIP  pkg 0402LF  page 77 : A = PVDD18_S5_P0 ; B = SPI_CPU0_CS0_N
R6212  Q_RES  2.2K 5% CHIP  pkg 0402LF  page 250 : A = P3V3_AUX ; B = SMB_USB_CPU0_HUB1_SDA
R1111  Q_RES  4.7K 5% EMPTY  pkg 0201LF  page 309 : A = P1V8_CPU0_RT_1D ; B = GPIO2_RT_CPU0_P3

(kicad_pcb
	(version 20260206)
	(generator "pcbnew")
	(generator_version "10.0")
	(general
		(thickness 1.6)
		(legacy_teardrops no)
	)
	(paper "A4")
	(title_block
		(title "04192023_DAF0TMB3IC0_F0TG_MB_C_brd_V02_OCP.brd")
		(comment 1 "Grand Teton / footprints 590-592 of 8354")
	)
	(layers
		(0 "F.Cu" signal "TOP")
		(4 "In1.Cu" signal "GND")
		(6 "In2.Cu" signal "IN1")
		(8 "In3.Cu" signal "GND1")
		(10 "In4.Cu" signal "IN2")
		(12 "In5.Cu" signal "GND2")
		(14 "In6.Cu" signal "IN3")
		(16 "In7.Cu" signal "GND3")
		(18 "In8.Cu" signal "VCC")
		(20 "In9.Cu" signal "VCC1")
		(22 "In10.Cu" signal "GND4")
		(24 "In11.Cu" signal "IN4")
		(26 "In12.Cu" signal "GND5")
		(28 "In13.Cu" signal "IN5")
		(30 "In14.Cu" signal "GND6")
		(32 "In15.Cu" signal "IN6")
		(34 "In16.Cu" signal "GND7")
		(2 "B.Cu" signal "BOTTOM")
		(9 "F.Adhes" user "F.Adhesive")
		(11 "B.Adhes" user "B.Adhesive")
		(13 "F.Paste" user "Package Geometry/Pastemask Top")
		(15 "B.Paste" user "Package Geometry/Pastemask Bottom")
		(5 "F.SilkS" user "Ref Des/Silkscreen Top")
		(7 "B.SilkS" user "Ref Des/Silkscreen Bottom")
		(1 "F.Mask" user "Board Geometry/Soldermask Top")
		(3 "B.Mask" user "Board Geometry/Soldermask Bottom")
		(17 "Dwgs.User" user "User.Drawings")
		(19 "Cmts.User" user "User.Comments")
		(21 "Eco1.User" user "User.Eco1")
		(23 "Eco2.User" user "User.Eco2")
		(25 "Edge.Cuts" user "Board Geometry/Outline")
		(27 "Margin" user)
		(31 "F.CrtYd" user "Package Geometry/Place Bound Top")
		(29 "B.CrtYd" user "Package Geometry/Place Bound Bottom")
		(35 "F.Fab" user "Ref Des/Assembly Top")
		(33 "B.Fab" user "Ref Des/Assembly Bottom")
	)
	(footprint ""
		(layer "F.Cu")
		(at 277.608792 -121.37517 -90)
		(property "Reference" "R6212"
			(at 0 0 270)
			(layer "F.SilkS")
			(hide yes)
			(effects
				(font
					(size 1.27 1.27)
				)
			)
		)
		(property "Value" ""
			(at 0 0 270)
			(layer "F.Fab")
			(effects
				(font
					(size 1.27 1.27)
				)
			)
		)
		(duplicate_pad_numbers_are_jumpers no)
		(fp_line
			(start -0.7874 0.4064)
			(end -0.7874 -0.4064)
			(stroke
				(width 0.1524)
				(type default)
			)
			(layer "F.SilkS")
		)
		(fp_line
			(start 0.7874 0.4064)
			(end -0.7874 0.4064)
			(stroke
				(width 0.1524)
				(type default)
			)
			(layer "F.SilkS")
		)
		(fp_line
			(start -0.7874 -0.4064)
			(end 0.7874 -0.4064)
			(stroke
				(width 0.1524)
				(type default)
			)
			(layer "F.SilkS")
		)
		(fp_line
			(start 0.7874 -0.4064)
			(end 0.7874 0.4064)
			(stroke
				(width 0.1524)
				(type default)
			)
			(layer "F.SilkS")
		)
		(fp_line
			(start -0.67945 0.3048)
			(end -0.67945 -0.305054)
			(stroke
				(width 0.1)
				(type default)
			)
			(layer "F.Fab")
		)
		(fp_line
			(start -0.12065 0.3048)
			(end -0.67945 0.3048)
			(stroke
				(width 0.1)
				(type default)
			)
			(layer "F.Fab")
		)
		(fp_line
			(start 0.120396 0.3048)
			(end 0.120396 0.2794)
			(stroke
				(width 0.1)
				(type default)
			)
			(layer "F.Fab")
		)
		(fp_line
			(start 0.67945 0.3048)
			(end 0.120396 0.3048)
			(stroke
				(width 0.1)
				(type default)
			)
			(layer "F.Fab")
		)
		(fp_line
			(start -0.12065 0.2794)
			(end -0.12065 0.3048)
			(stroke
				(width 0.1)
				(type default)
			)
			(layer "F.Fab")
		)
		(fp_line
			(start 0.120396 0.2794)
			(end -0.12065 0.2794)
			(stroke
				(width 0.1)
				(type default)
			)
			(layer "F.Fab")
		)
		(fp_line
			(start -0.12065 -0.2794)
			(end 0.12065 -0.2794)
			(stroke
				(width 0.1)
				(type default)
			)
			(layer "F.Fab")
		)
		(fp_line
			(start 0.12065 -0.2794)
			(end 0.12065 -0.3048)
			(stroke
				(width 0.1)
				(type default)
			)
			(layer "F.Fab")
		)
		(fp_line
			(start 0.12065 -0.3048)
			(end 0.67945 -0.3048)
			(stroke
				(width 0.1)
				(type default)
			)
			(layer "F.Fab")
		)
		(fp_line
			(start 0.67945 -0.3048)
			(end 0.67945 0.3048)
			(stroke
				(width 0.1)
				(type default)
			)
			(layer "F.Fab")
		)
		(fp_line
			(start -0.67945 -0.305054)
			(end -0.12065 -0.305054)
			(stroke
				(width 0.1)
				(type default)
			)
			(layer "F.Fab")
		)
		(fp_line
			(start -0.12065 -0.305054)
			(end -0.12065 -0.2794)
			(stroke
				(width 0.1)
				(type default)
			)
			(layer "F.Fab")
		)
		(pad "1" smd circle
			(at -0.40005 0 270)
			(size 0 0)
			(layers "F.Cu" "F.Mask" "F.Paste")
			(net "P3V3_AUX")
		)
		(pad "2" smd circle
			(at 0.40005 0 270)
			(size 0 0)
			(layers "F.Cu" "F.Mask" "F.Paste")
			(net "SMB_USB_CPU0_HUB1_SDA")
		)
	)
	(footprint ""
		(layer "F.Cu")
		(at 365.09579 -393.86256)
		(property "Reference" "R1111"
			(at 0 0 0)
			(layer "F.SilkS")
			(hide yes)
			(effects
				(font
					(size 1.27 1.27)
				)
			)
		)
		(property "Value" ""
			(at 0 0 0)
			(layer "F.Fab")
			(effects
				(font
					(size 1.27 1.27)
				)
			)
		)
		(duplicate_pad_numbers_are_jumpers no)
		(fp_line
			(start -0.32512 -0.175006)
			(end 0.32512 -0.175006)
			(stroke
				(width 0.1)
				(type default)
			)
			(layer "F.Fab")
		)
		(fp_line
			(start -0.32512 0.175006)
			(end -0.32512 -0.175006)
			(stroke
				(width 0.1)
				(type default)
			)
			(layer "F.Fab")
		)
		(fp_line
			(start 0.32512 -0.175006)
			(end 0.32512 0.175006)
			(stroke
				(width 0.1)
				(type default)
			)
			(layer "F.Fab")
		)
		(fp_line
			(start 0.32512 0.175006)
			(end -0.32512 0.175006)
			(stroke
				(width 0.1)
				(type default)
			)
			(layer "F.Fab")
		)
		(pad "1" smd rect
			(at -0.2667 0)
			(size 0.3048 0.381)
			(layers "F.Cu" "F.Mask" "F.Paste")
			(net "P1V8_CPU0_RT_1D")
		)
		(pad "2" smd rect
			(at 0.2667 0 180)
			(size 0.3048 0.381)
			(layers "F.Cu" "F.Mask" "F.Paste")
			(net "GPIO2_RT_CPU0_P3")
		)
	)
	(footprint ""
		(layer "F.Cu")
		(at 264.478516 -131.067556 180)
		(property "Reference" "R811"
			(at 0 0 180)
			(layer "F.SilkS")
			(hide yes)
			(effects
				(font
					(size 1.27 1.27)
				)
			)
		)
		(property "Value" ""
			(at 0 0 180)
			(layer "F.Fab")
			(effects
				(font
					(size 1.27 1.27)
				)
			)
		)
		(duplicate_pad_numbers_are_jumpers no)
		(fp_line
			(start 0.7874 0.4064)
			(end -0.7874 0.4064)
			(stroke
				(width 0.1524)
				(type default)
			)
			(layer "F.SilkS")
		)
		(fp_line
			(start 0.7874 -0.4064)
			(end 0.7874 0.4064)
			(stroke
				(width 0.1524)
				(type default)
			)
			(layer "F.SilkS")
		)
		(fp_line
			(start -0.7874 0.4064)
			(end -0.7874 -0.4064)
			(stroke
				(width 0.1524)
				(type default)
			)
			(layer "F.SilkS")
		)
		(fp_line
			(start -0.7874 -0.4064)
			(end 0.7874 -0.4064)
			(stroke
				(width 0.1524)
				(type default)
			)
			(layer "F.SilkS")
		)
		(fp_line
			(start 0.67945 0.3048)
			(end 0.120396 0.3048)
			(stroke
				(width 0.1)
				(type default)
			)
			(layer "F.Fab")
		)
		(fp_line
			(start 0.67945 -0.3048)
			(end 0.67945 0.3048)
			(stroke
				(width 0.1)
				(type default)
			)
			(layer "F.Fab")
		)
		(fp_line
			(start 0.12065 -0.2794)
			(end 0.12065 -0.3048)
			(stroke
				(width 0.1)
				(type default)
			)
			(layer "F.Fab")
		)
		(fp_line
			(start 0.12065 -0.3048)
			(end 0.67945 -0.3048)
			(stroke
				(width 0.1)
				(type default)
			)
			(layer "F.Fab")
		)
		(fp_line
			(start 0.120396 0.3048)
			(end 0.120396 0.2794)
			(stroke
				(width 0.1)
				(type default)
			)
			(layer "F.Fab")
		)
		(fp_line
			(start 0.120396 0.2794)
			(end -0.12065 0.2794)
			(stroke
				(width 0.1)
				(type default)
			)
			(layer "F.Fab")
		)
		(fp_line
			(start -0.12065 0.3048)
			(end -0.67945 0.3048)
			(stroke
				(width 0.1)
				(type default)
			)
			(layer "F.Fab")
		)
		(fp_line
			(start -0.12065 0.2794)
			(end -0.12065 0.3048)
			(stroke
				(width 0.1)
				(type default)
			)
			(layer "F.Fab")
		)
		(fp_line
			(start -0.12065 -0.2794)
			(end 0.12065 -0.2794)
			(stroke
				(width 0.1)
				(type default)
			)
			(layer "F.Fab")
		)
		(fp_line
			(start -0.12065 -0.305054)
			(end -0.12065 -0.2794)
			(stroke
				(width 0.1)
				(type default)
			)
			(layer "F.Fab")
		)
		(fp_line
			(start -0.67945 0.3048)
			(end -0.67945 -0.305054)
			(stroke
				(width 0.1)
				(type default)
			)
			(layer "F.Fab")
		)
		(fp_line
			(start -0.67945 -0.305054)
			(end -0.12065 -0.305054)
			(stroke
				(width 0.1)
				(type default)
			)
			(layer "F.Fab")
		)
		(pad "1" smd circle
			(at -0.40005 0 180)
			(size 0 0)
			(layers "F.Cu" "F.Mask" "F.Paste")
			(net "PVDD18_S5_P0")
		)
		(pad "2" smd circle
			(at 0.40005 0 180)
			(size 0 0)
			(layers "F.Cu" "F.Mask" "F.Paste")
			(net "SPI_CPU0_CS0_N")
		)
	)
)
